(kicad_pcb
	(version 20241229)
	(generator "pcbnew")
	(generator_version "9.0")
	(general
		(thickness 1.711)
		(legacy_teardrops no)
	)
	(paper "A4")
	(title_block
		(title "Antmicro Baseboard for Jetson AGX Thor")
		(date "2026-02-18")
		(rev "1.1.0")
		(company "Antmicro Ltd")
		(comment 1 "www.antmicro.com")
		(comment 9 "footprints 159-163 of 1170")
	)
	(layers
		(0 "F.Cu" signal)
		(4 "In1.Cu" signal)
		(6 "In2.Cu" signal)
		(8 "In3.Cu" signal)
		(10 "In4.Cu" jumper)
		(12 "In5.Cu" signal)
		(14 "In6.Cu" signal)
		(16 "In7.Cu" signal)
		(18 "In8.Cu" signal)
		(2 "B.Cu" signal)
		(9 "F.Adhes" user "F.Adhesive")
		(11 "B.Adhes" user "B.Adhesive")
		(13 "F.Paste" user)
		(15 "B.Paste" user)
		(5 "F.SilkS" user "F.Silkscreen")
		(7 "B.SilkS" user "B.Silkscreen")
		(1 "F.Mask" user)
		(3 "B.Mask" user)
		(17 "Dwgs.User" user "User.Drawings")
		(19 "Cmts.User" user "User.Comments")
		(21 "Eco1.User" user "User.Eco1")
		(23 "Eco2.User" user "User.Eco2")
		(25 "Edge.Cuts" user)
		(27 "Margin" user)
		(31 "F.CrtYd" user "F.Courtyard")
		(29 "B.CrtYd" user "B.Courtyard")
		(35 "F.Fab" user)
		(33 "B.Fab" user)
	)
	(footprint "antmicro-footprints:R_0402_1005Metric"
		(layer "F.Cu")
		(at 88 57.5 180)
		(descr "Resistor SMD 0402")
		(tags "resistor SMD 0402")
		(property "Reference" "R301"
			(at 16.35 -8.65 0)
			(layer "F.SilkS")
			(effects
				(font
					(size 0.7 0.7)
					(thickness 0.15)
				)
				(justify right top)
			)
		)
		(property "Value" "R_0R_0402"
			(at -1.011843 1.772047 0)
			(layer "F.Fab")
			(effects
				(font
					(size 0.7 0.7)
					(thickness 0.15)
				)
				(justify right top)
			)
		)
		(property "Datasheet" "https://industrial.panasonic.com/cdbs/www-data/pdf/RDA0000/AOA0000C301.pdf"
			(at 0 0 0)
			(layer "F.Fab")
			(hide yes)
			(effects
				(font
					(size 1.27 1.27)
					(thickness 0.15)
				)
			)
		)
		(property "Description" "SMD Chip Resistor, Jumper, 0 ohm, 100 mW, 0402 [1005 Metric], Thick Film, General Purpose"
			(at 0 0 0)
			(layer "F.Fab")
			(hide yes)
			(effects
				(font
					(size 1.27 1.27)
					(thickness 0.15)
				)
			)
		)
		(property "MPN" "ERJ2GE0R00X"
			(at 0 0 180)
			(unlocked yes)
			(layer "F.Fab")
			(hide yes)
			(effects
				(font
					(size 1 1)
					(thickness 0.15)
				)
			)
		)
		(property "Manufacturer" "Panasonic"
			(at 0 0 180)
			(unlocked yes)
			(layer "F.Fab")
			(hide yes)
			(effects
				(font
					(size 1 1)
					(thickness 0.15)
				)
			)
		)
		(property "License" "Apache-2.0"
			(at 0 0 180)
			(unlocked yes)
			(layer "F.Fab")
			(hide yes)
			(effects
				(font
					(size 1 1)
					(thickness 0.15)
				)
			)
		)
		(property "Author" "Antmicro"
			(at 0 0 180)
			(unlocked yes)
			(layer "F.Fab")
			(hide yes)
			(effects
				(font
					(size 1 1)
					(thickness 0.15)
				)
			)
		)
		(property "Val" "0R"
			(at 0 0 180)
			(unlocked yes)
			(layer "F.Fab")
			(hide yes)
			(effects
				(font
					(size 1 1)
					(thickness 0.15)
				)
			)
		)
		(property "Tolerance" "~"
			(at 0 0 180)
			(unlocked yes)
			(layer "F.Fab")
			(hide yes)
			(effects
				(font
					(size 1 1)
					(thickness 0.15)
				)
			)
		)
		(property "Current" "1A"
			(at 0 0 180)
			(unlocked yes)
			(layer "F.Fab")
			(hide yes)
			(effects
				(font
					(size 1 1)
					(thickness 0.15)
				)
			)
		)
		(sheetname "/SoM_Power/")
		(sheetfile "som_power.kicad_sch")
		(attr smd)
		(fp_rect
			(start -0.925 -0.47)
			(end 0.925 0.47)
			(stroke
				(width 0.05)
				(type default)
			)
			(fill no)
			(layer "F.CrtYd")
		)
		(fp_rect
			(start -0.5 -0.25)
			(end 0.5 0.25)
			(stroke
				(width 0.15)
				(type solid)
			)
			(fill no)
			(layer "F.Fab")
		)
		(fp_text user "${REFERENCE}"
			(at -0.95 3.168 0)
			(layer "F.Fab")
			(effects
				(font
					(size 0.7 0.7)
					(thickness 0.15)
				)
				(justify right top)
			)
		)
		(fp_text user "License: Apache-2.0"
			(at -0.95 5.169 0)
			(layer "F.Fab")
			(effects
				(font
					(size 0.7 0.7)
					(thickness 0.15)
				)
				(justify right top)
			)
		)
		(fp_text user "Author: Antmicro"
			(at -0.95 4.169 0)
			(layer "F.Fab")
			(effects
				(font
					(size 0.7 0.7)
					(thickness 0.15)
				)
				(justify right top)
			)
		)
		(pad "1" smd roundrect
			(at -0.48 0 180)
			(size 0.59 0.64)
			(layers "F.Cu" "F.Mask" "F.Paste")
			(roundrect_rratio 0.25)
			(net 1033 "Net-(U70-OUT)")
			(pintype "passive")
		)
		(pad "2" smd roundrect
			(at 0.48 0 180)
			(size 0.59 0.64)
			(layers "F.Cu" "F.Mask" "F.Paste")
			(roundrect_rratio 0.25)
			(net 1382 "Net-(R300-Pad2)")
			(pintype "passive")
		)
	)
	(footprint "antmicro-footprints:TP_SMD_0.75mm"
		(layer "F.Cu")
		(at 79.4 76.8 180)
		(property "Reference" "TP73"
			(at -0.49 -3.34 270)
			(layer "F.SilkS")
			(effects
				(font
					(size 0.7 0.7)
					(thickness 0.15)
				)
				(justify left bottom)
			)
		)
		(property "Value" "TP_0.75mm_SMD"
			(at 0 1.2 180)
			(layer "F.Fab")
			(effects
				(font
					(size 0.7 0.7)
					(thickness 0.15)
				)
				(justify left bottom)
			)
		)
		(property "Description" "SMT test point"
			(at 0 0 180)
			(layer "F.Fab")
			(hide yes)
			(effects
				(font
					(size 1.27 1.27)
					(thickness 0.15)
				)
			)
		)
		(property "MPN" ""
			(at 0 0 180)
			(unlocked yes)
			(layer "F.Fab")
			(hide yes)
			(effects
				(font
					(size 1 1)
					(thickness 0.15)
				)
			)
		)
		(property "Manufacturer" ""
			(at 0 0 180)
			(unlocked yes)
			(layer "F.Fab")
			(hide yes)
			(effects
				(font
					(size 1 1)
					(thickness 0.15)
				)
			)
		)
		(property "Author" "Antmicro"
			(at 0 0 180)
			(unlocked yes)
			(layer "F.Fab")
			(hide yes)
			(effects
				(font
					(size 1 1)
					(thickness 0.15)
				)
			)
		)
		(property "License" "Apache-2.0"
			(at 0 0 180)
			(unlocked yes)
			(layer "F.Fab")
			(hide yes)
			(effects
				(font
					(size 1 1)
					(thickness 0.15)
				)
			)
		)
		(sheetname "/Expansion connector/")
		(sheetfile "expansion_connector.kicad_sch")
		(attr exclude_from_pos_files exclude_from_bom)
		(fp_circle
			(center 0 0)
			(end 0.475 0)
			(stroke
				(width 0.05)
				(type default)
			)
			(fill no)
			(layer "F.CrtYd")
		)
		(fp_text user "Author: Antmicro"
			(at -0.4 3.901 180)
			(layer "F.Fab")
			(effects
				(font
					(size 0.7 0.7)
					(thickness 0.15)
				)
				(justify left bottom)
			)
		)
		(fp_text user "${REFERENCE}"
			(at -0.4 2.7 180)
			(layer "F.Fab")
			(effects
				(font
					(size 0.7 0.7)
					(thickness 0.15)
				)
				(justify left bottom)
			)
		)
		(fp_text user "License: Apache-2.0"
			(at -0.4 5.101 180)
			(layer "F.Fab")
			(effects
				(font
					(size 0.7 0.7)
					(thickness 0.15)
				)
				(justify left bottom)
			)
		)
		(pad "1" smd circle
			(at 0 0 180)
			(size 0.75 0.75)
			(layers "F.Cu" "F.Mask")
			(net 659 "Net-(J18-PadB01)")
			(pinfunction "1")
			(pintype "passive")
		)
	)
	(footprint "antmicro-footprints:R_0402_1005Metric"
		(layer "F.Cu")
		(at 182.764468 87.835 90)
		(descr "Resistor SMD 0402")
		(tags "resistor SMD 0402")
		(property "Reference" "R69"
			(at -0.84 2.38 90)
			(layer "F.SilkS")
			(effects
				(font
					(size 0.7 0.7)
					(thickness 0.15)
				)
				(justify left bottom)
			)
		)
		(property "Value" "R_255k_0402"
			(at -1.011843 1.772047 90)
			(layer "F.Fab")
			(effects
				(font
					(size 0.7 0.7)
					(thickness 0.15)
				)
				(justify left bottom)
			)
		)
		(property "Datasheet" "https://www.bourns.com/docs/product-datasheets/cr.pdf"
			(at 0 0 90)
			(layer "F.Fab")
			(hide yes)
			(effects
				(font
					(size 1.27 1.27)
					(thickness 0.15)
				)
			)
		)
		(property "Description" "SMD Chip Resistor, 255 kohm, ± 1%, 100 mW, 0402 [1005 Metric], Thick Film, Precision"
			(at 0 0 90)
			(layer "F.Fab")
			(hide yes)
			(effects
				(font
					(size 1.27 1.27)
					(thickness 0.15)
				)
			)
		)
		(property "MPN" "CR0402-FX-2553GLF"
			(at 0 0 90)
			(unlocked yes)
			(layer "F.Fab")
			(hide yes)
			(effects
				(font
					(size 1 1)
					(thickness 0.15)
				)
			)
		)
		(property "Manufacturer" "Bourns"
			(at 0 0 90)
			(unlocked yes)
			(layer "F.Fab")
			(hide yes)
			(effects
				(font
					(size 1 1)
					(thickness 0.15)
				)
			)
		)
		(property "License" "Apache-2.0"
			(at 0 0 90)
			(unlocked yes)
			(layer "F.Fab")
			(hide yes)
			(effects
				(font
					(size 1 1)
					(thickness 0.15)
				)
			)
		)
		(property "Author" "Antmicro"
			(at 0 0 90)
			(unlocked yes)
			(layer "F.Fab")
			(hide yes)
			(effects
				(font
					(size 1 1)
					(thickness 0.15)
				)
			)
		)
		(property "Val" "255k"
			(at 0 0 90)
			(unlocked yes)
			(layer "F.Fab")
			(hide yes)
			(effects
				(font
					(size 1 1)
					(thickness 0.15)
				)
			)
		)
		(property "Tolerance" "1%"
			(at 0 0 90)
			(unlocked yes)
			(layer "F.Fab")
			(hide yes)
			(effects
				(font
					(size 1 1)
					(thickness 0.15)
				)
			)
		)
		(component_classes
			(class "DCDC_SOM")
		)
		(sheetname "/DCDC/")
		(sheetfile "dcdc.kicad_sch")
		(attr smd)
		(fp_rect
			(start -0.925 -0.47)
			(end 0.925 0.47)
			(stroke
				(width 0.05)
				(type default)
			)
			(fill no)
			(layer "F.CrtYd")
		)
		(fp_rect
			(start -0.5 -0.25)
			(end 0.5 0.25)
			(stroke
				(width 0.15)
				(type solid)
			)
			(fill no)
			(layer "F.Fab")
		)
		(fp_text user "${REFERENCE}"
			(at -0.95 3.168 90)
			(layer "F.Fab")
			(effects
				(font
					(size 0.7 0.7)
					(thickness 0.15)
				)
				(justify left bottom)
			)
		)
		(fp_text user "Author: Antmicro"
			(at -0.95 4.169 90)
			(layer "F.Fab")
			(effects
				(font
					(size 0.7 0.7)
					(thickness 0.15)
				)
				(justify left bottom)
			)
		)
		(fp_text user "License: Apache-2.0"
			(at -0.95 5.169 90)
			(layer "F.Fab")
			(effects
				(font
					(size 0.7 0.7)
					(thickness 0.15)
				)
				(justify left bottom)
			)
		)
		(pad "1" smd roundrect
			(at -0.48 0 90)
			(size 0.59 0.64)
			(layers "F.Cu" "F.Mask" "F.Paste")
			(roundrect_rratio 0.25)
			(net 1219 "/DCDC/16V_FB")
			(pintype "passive")
		)
		(pad "2" smd roundrect
			(at 0.48 0 90)
			(size 0.59 0.64)
			(layers "F.Cu" "F.Mask" "F.Paste")
			(roundrect_rratio 0.25)
			(net 903 "/DCDC/16V_OUT")
			(pintype "passive")
		)
	)
	(footprint "antmicro-footprints:C_0805_2012Metric"
		(layer "F.Cu")
		(at 174.49 146.32 -90)
		(descr "Capacitor SMD 0805")
		(tags "capacitor SMD 0805")
		(property "Reference" "C307"
			(at 1.89 0.13 90)
			(layer "F.SilkS")
			(effects
				(font
					(size 0.7 0.7)
					(thickness 0.15)
				)
				(justify right top)
			)
		)
		(property "Value" "C_22u_25V_0805"
			(at -2.055717 1.963152 90)
			(layer "F.Fab")
			(effects
				(font
					(size 0.7 0.7)
					(thickness 0.15)
				)
				(justify right top)
			)
		)
		(property "Datasheet" "https://product.samsungsem.com/mlcc/CL21A226MAYNNN.do"
			(at 0 0 90)
			(layer "F.Fab")
			(hide yes)
			(effects
				(font
					(size 1.27 1.27)
					(thickness 0.15)
				)
			)
		)
		(property "Description" "SMT Multilayer Ceramic Capacitor, 22uF, +/-20%, 25V, X5R, 0805 [2012 Metric]"
			(at 0 0 90)
			(layer "F.Fab")
			(hide yes)
			(effects
				(font
					(size 1.27 1.27)
					(thickness 0.15)
				)
			)
		)
		(property "Manufacturer" "Samsung Electro-Mechanics"
			(at 0 0 270)
			(unlocked yes)
			(layer "F.Fab")
			(hide yes)
			(effects
				(font
					(size 1 1)
					(thickness 0.15)
				)
			)
		)
		(property "MPN" "CL21A226MAYNNNE"
			(at 0 0 270)
			(unlocked yes)
			(layer "F.Fab")
			(hide yes)
			(effects
				(font
					(size 1 1)
					(thickness 0.15)
				)
			)
		)
		(property "Val" "22u"
			(at 0 0 270)
			(unlocked yes)
			(layer "F.Fab")
			(hide yes)
			(effects
				(font
					(size 1 1)
					(thickness 0.15)
				)
			)
		)
		(property "License" "Apache-2.0"
			(at 0 0 270)
			(unlocked yes)
			(layer "F.Fab")
			(hide yes)
			(effects
				(font
					(size 1 1)
					(thickness 0.15)
				)
			)
		)
		(property "Author" "Antmicro"
			(at 0 0 270)
			(unlocked yes)
			(layer "F.Fab")
			(hide yes)
			(effects
				(font
					(size 1 1)
					(thickness 0.15)
				)
			)
		)
		(property "Voltage" "25V"
			(at 0 0 270)
			(unlocked yes)
			(layer "F.Fab")
			(hide yes)
			(effects
				(font
					(size 1 1)
					(thickness 0.15)
				)
			)
		)
		(property "Dielectric" "X5R"
			(at 0 0 270)
			(unlocked yes)
			(layer "F.Fab")
			(hide yes)
			(effects
				(font
					(size 1 1)
					(thickness 0.15)
				)
			)
		)
		(property "Public" "False"
			(at 0 0 270)
			(unlocked yes)
			(layer "F.Fab")
			(hide yes)
			(effects
				(font
					(size 1 1)
					(thickness 0.15)
				)
			)
		)
		(sheetname "/DCDC/")
		(sheetfile "dcdc.kicad_sch")
		(attr smd)
		(fp_line
			(start -0.3 0.7)
			(end 0.3 0.7)
			(stroke
				(width 0.15)
				(type solid)
			)
			(layer "F.SilkS")
		)
		(fp_line
			(start -0.3 -0.7)
			(end 0.3 -0.7)
			(stroke
				(width 0.15)
				(type solid)
			)
			(layer "F.SilkS")
		)
		(fp_rect
			(start 1.95 -0.9)
			(end -1.95 0.9)
			(stroke
				(width 0.05)
				(type default)
			)
			(fill no)
			(layer "F.CrtYd")
		)
		(fp_rect
			(start -0.95 -0.675)
			(end 0.95 0.675)
			(stroke
				(width 0.15)
				(type solid)
			)
			(fill no)
			(layer "F.Fab")
		)
		(fp_text user "${REFERENCE}"
			(at -1.9 3.947 90)
			(layer "F.Fab")
			(effects
				(font
					(size 0.7 0.7)
					(thickness 0.15)
				)
				(justify right top)
			)
		)
		(fp_text user "Author: Antmicro"
			(at -1.9 5.947 90)
			(layer "F.Fab")
			(effects
				(font
					(size 0.7 0.7)
					(thickness 0.15)
				)
				(justify right top)
			)
		)
		(fp_text user "License: Apache-2.0"
			(at -1.9 4.947 90)
			(layer "F.Fab")
			(effects
				(font
					(size 0.7 0.7)
					(thickness 0.15)
				)
				(justify right top)
			)
		)
		(pad "1" smd roundrect
			(at -1.1 0 270)
			(size 1.2 1.3)
			(layers "F.Cu" "F.Mask" "F.Paste")
			(roundrect_rratio 0.25)
			(net 1 "GND")
			(pintype "passive")
		)
		(pad "2" smd roundrect
			(at 1.1 0 270)
			(size 1.2 1.3)
			(layers "F.Cu" "F.Mask" "F.Paste")
			(roundrect_rratio 0.25)
			(net 880 "/DCDC/12V_OUT")
			(pintype "passive")
		)
	)
	(footprint "antmicro-footprints:C_0402_1005Metric"
		(layer "F.Cu")
		(at 89.12 90.45)
		(descr "Capacitor SMD 0402")
		(tags "capacitor SMD 0402")
		(property "Reference" "C338"
			(at -3.82 0.45 0)
			(layer "F.SilkS")
			(effects
				(font
					(size 0.7 0.7)
					(thickness 0.15)
				)
				(justify left bottom)
			)
		)
		(property "Value" "C_100n_0402"
			(at -1.022927 2.155213 0)
			(layer "F.Fab")
			(effects
				(font
					(size 0.7 0.7)
					(thickness 0.15)
				)
				(justify left bottom)
			)
		)
		(property "Datasheet" "https://www.murata.com/products/productdetail?partno=GRM155R61H104KE14%23"
			(at 0 0 0)
			(layer "F.Fab")
			(hide yes)
			(effects
				(font
					(size 1.27 1.27)
					(thickness 0.15)
				)
			)
		)
		(property "Description" "SMD Multilayer Ceramic Capacitor, 0.1 µF, 50 V, 0402 [1005 Metric], ± 10%, X5R, GRM Series"
			(at 0 0 0)
			(layer "F.Fab")
			(hide yes)
			(effects
				(font
					(size 1.27 1.27)
					(thickness 0.15)
				)
			)
		)
		(property "Manufacturer" "Murata"
			(at 0 0 0)
			(unlocked yes)
			(layer "F.Fab")
			(hide yes)
			(effects
				(font
					(size 1 1)
					(thickness 0.15)
				)
			)
		)
		(property "MPN" "GRM155R61H104KE14D"
			(at 0 0 0)
			(unlocked yes)
			(layer "F.Fab")
			(hide yes)
			(effects
				(font
					(size 1 1)
					(thickness 0.15)
				)
			)
		)
		(property "Val" "100n"
			(at 0 0 0)
			(unlocked yes)
			(layer "F.Fab")
			(hide yes)
			(effects
				(font
					(size 1 1)
					(thickness 0.15)
				)
			)
		)
		(property "License" "Apache-2.0"
			(at 0 0 0)
			(unlocked yes)
			(layer "F.Fab")
			(hide yes)
			(effects
				(font
					(size 1 1)
					(thickness 0.15)
				)
			)
		)
		(property "Author" "Antmicro"
			(at 0 0 0)
			(unlocked yes)
			(layer "F.Fab")
			(hide yes)
			(effects
				(font
					(size 1 1)
					(thickness 0.15)
				)
			)
		)
		(property "Voltage" "50V"
			(at 0 0 0)
			(unlocked yes)
			(layer "F.Fab")
			(hide yes)
			(effects
				(font
					(size 1 1)
					(thickness 0.15)
				)
			)
		)
		(property "Dielectric" "X5R"
			(at 0 0 0)
			(unlocked yes)
			(layer "F.Fab")
			(hide yes)
			(effects
				(font
					(size 1 1)
					(thickness 0.15)
				)
			)
		)
		(sheetname "/SoM_IO2/")
		(sheetfile "som_io2.kicad_sch")
		(attr smd)
		(fp_rect
			(start -0.925 -0.47)
			(end 0.925 0.47)
			(stroke
				(width 0.05)
				(type default)
			)
			(fill no)
			(layer "F.CrtYd")
		)
		(fp_line
			(start -0.494 -0.25)
			(end 0.504 -0.25)
			(stroke
				(width 0.15)
				(type solid)
			)
			(layer "F.Fab")
		)
		(fp_line
			(start -0.494 0.248)
			(end -0.494 -0.25)
			(stroke
				(width 0.15)
				(type solid)
			)
			(layer "F.Fab")
		)
		(fp_line
			(start 0.504 -0.25)
			(end 0.504 0.248)
			(stroke
				(width 0.15)
				(type solid)
			)
			(layer "F.Fab")
		)
		(fp_line
			(start 0.504 0.248)
			(end -0.494 0.248)
			(stroke
				(width 0.15)
				(type solid)
			)
			(layer "F.Fab")
		)
		(fp_text user "License: Apache-2.0"
			(at -0.939 5.799 0)
			(layer "F.Fab")
			(effects
				(font
					(size 0.7 0.7)
					(thickness 0.15)
				)
				(justify left bottom)
			)
		)
		(fp_text user "Author: Antmicro"
			(at -0.939 3.399 0)
			(layer "F.Fab")
			(effects
				(font
					(size 0.7 0.7)
					(thickness 0.15)
				)
				(justify left bottom)
			)
		)
		(fp_text user "${REFERENCE}"
			(at -0.939 4.599 0)
			(layer "F.Fab")
			(effects
				(font
					(size 0.7 0.7)
					(thickness 0.15)
				)
				(justify left bottom)
			)
		)
		(pad "1" smd roundrect
			(at -0.48 0)
			(size 0.59 0.64)
			(layers "F.Cu" "F.Mask" "F.Paste")
			(roundrect_rratio 0.25)
			(net 737 "/Expansion connector/DP2.TX0-")
			(pintype "passive")
		)
		(pad "2" smd roundrect
			(at 0.48 0)
			(size 0.59 0.64)
			(layers "F.Cu" "F.Mask" "F.Paste")
			(roundrect_rratio 0.25)
			(net 1258 "/SoM_IO2/DP2.TX0_C-")
			(pintype "passive")
		)
	)
)
